(kicad_pcb
	(version 20260206)
	(generator "pcbnew")
	(generator_version "10.0")
	(general
		(thickness 1.6)
		(legacy_teardrops no)
	)
	(paper "A4")
	(title_block
		(title "04192023_DAF0TMB3IC0_F0TG_MB_C_brd_V02_OCP.brd")
		(comment 1 "Grand Teton / footprint 1456 of 8354 (J29), pads 1-113 of 291")
	)
	(layers
		(0 "F.Cu" signal "TOP")
		(4 "In1.Cu" signal "GND")
		(6 "In2.Cu" signal "IN1")
		(8 "In3.Cu" signal "GND1")
		(10 "In4.Cu" signal "IN2")
		(12 "In5.Cu" signal "GND2")
		(14 "In6.Cu" signal "IN3")
		(16 "In7.Cu" signal "GND3")
		(18 "In8.Cu" signal "VCC")
		(20 "In9.Cu" signal "VCC1")
		(22 "In10.Cu" signal "GND4")
		(24 "In11.Cu" signal "IN4")
		(26 "In12.Cu" signal "GND5")
		(28 "In13.Cu" signal "IN5")
		(30 "In14.Cu" signal "GND6")
		(32 "In15.Cu" signal "IN6")
		(34 "In16.Cu" signal "GND7")
		(2 "B.Cu" signal "BOTTOM")
		(9 "F.Adhes" user "F.Adhesive")
		(11 "B.Adhes" user "B.Adhesive")
		(13 "F.Paste" user "Package Geometry/Pastemask Top")
		(15 "B.Paste" user "Package Geometry/Pastemask Bottom")
		(5 "F.SilkS" user "Ref Des/Silkscreen Top")
		(7 "B.SilkS" user "Ref Des/Silkscreen Bottom")
		(1 "F.Mask" user "Board Geometry/Soldermask Top")
		(3 "B.Mask" user "Board Geometry/Soldermask Bottom")
		(17 "Dwgs.User" user "User.Drawings")
		(19 "Cmts.User" user "User.Comments")
		(21 "Eco1.User" user "User.Eco1")
		(23 "Eco2.User" user "User.Eco2")
		(25 "Edge.Cuts" user "Board Geometry/Outline")
		(27 "Margin" user)
		(31 "F.CrtYd" user "Package Geometry/Place Bound Top")
		(29 "B.CrtYd" user "Package Geometry/Place Bound Bottom")
		(35 "F.Fab" user "Ref Des/Assembly Top")
		(33 "B.Fab" user "Ref Des/Assembly Bottom")
	)
	(footprint ""
		(layer "F.Cu")
		(at 189.110112 -255.560322 180)
		(property "Reference" "J29"
			(at -2.7178 -81.857088 0)
			(unlocked yes)
			(layer "F.SilkS")
			(effects
				(font
					(size 0.7874 0.5842)
					(thickness 0.1524)
				)
			)
		)
		(property "Value" ""
			(at 0 0 180)
			(layer "F.Fab")
			(effects
				(font
					(size 1.27 1.27)
				)
			)
		)
		(duplicate_pad_numbers_are_jumpers no)
		(pad "1" smd rect
			(at -2.050034 -63.324994 90)
			(size 0.519938 1.4986)
			(layers "F.Cu" "F.Mask" "F.Paste")
			(net "P12V_MEM_CPU1")
		)
		(pad "2" smd rect
			(at -2.050034 -62.47511 90)
			(size 0.519938 1.4986)
			(layers "F.Cu" "F.Mask" "F.Paste")
			(net "Net_2382")
		)
		(pad "3" smd rect
			(at -2.050034 -61.624972 90)
			(size 0.519938 1.4986)
			(layers "F.Cu" "F.Mask" "F.Paste")
			(net "P3V3_AUX")
		)
		(pad "4" smd rect
			(at -2.050034 -60.775088 90)
			(size 0.519938 1.4986)
			(layers "F.Cu" "F.Mask" "F.Paste")
			(net "I3C_SPD_DDRJ_CPU1_SCL")
		)
		(pad "5" smd rect
			(at -2.050034 -59.92495 90)
			(size 0.519938 1.4986)
			(layers "F.Cu" "F.Mask" "F.Paste")
			(net "I3C_SPD_DDRJ_CPU1_SDA")
		)
		(pad "6" smd rect
			(at -2.050034 -59.075066 90)
			(size 0.519938 1.4986)
			(layers "F.Cu" "F.Mask" "F.Paste")
			(net "GND")
		)
		(pad "7" smd rect
			(at -2.050034 -58.224928 90)
			(size 0.519938 1.4986)
			(layers "F.Cu" "F.Mask" "F.Paste")
			(net "M_J_CPU1_SA_DQ<0>")
		)
		(pad "8" smd rect
			(at -2.050034 -57.375044 90)
			(size 0.519938 1.4986)
			(layers "F.Cu" "F.Mask" "F.Paste")
			(net "GND")
		)
		(pad "9" smd rect
			(at -2.050034 -56.524906 90)
			(size 0.519938 1.4986)
			(layers "F.Cu" "F.Mask" "F.Paste")
			(net "M_J_CPU1_SA_DQ<1>")
		)
		(pad "10" smd rect
			(at -2.050034 -55.675022 90)
			(size 0.519938 1.4986)
			(layers "F.Cu" "F.Mask" "F.Paste")
			(net "GND")
		)
		(pad "11" smd rect
			(at -2.050034 -54.824884 90)
			(size 0.519938 1.4986)
			(layers "F.Cu" "F.Mask" "F.Paste")
			(net "M_J_CPU1_SA_DQS_DP<0>")
		)
		(pad "12" smd rect
			(at -2.050034 -53.975 90)
			(size 0.519938 1.4986)
			(layers "F.Cu" "F.Mask" "F.Paste")
			(net "M_J_CPU1_SA_DQS_DN<0>")
		)
		(pad "13" smd rect
			(at -2.050034 -53.125116 90)
			(size 0.519938 1.4986)
			(layers "F.Cu" "F.Mask" "F.Paste")
			(net "GND")
		)
		(pad "14" smd rect
			(at -2.050034 -52.274978 90)
			(size 0.519938 1.4986)
			(layers "F.Cu" "F.Mask" "F.Paste")
			(net "M_J_CPU1_SA_DQ<4>")
		)
		(pad "15" smd rect
			(at -2.050034 -51.425094 90)
			(size 0.519938 1.4986)
			(layers "F.Cu" "F.Mask" "F.Paste")
			(net "GND")
		)
		(pad "16" smd rect
			(at -2.050034 -50.574956 90)
			(size 0.519938 1.4986)
			(layers "F.Cu" "F.Mask" "F.Paste")
			(net "M_J_CPU1_SA_DQ<5>")
		)
		(pad "17" smd rect
			(at -2.050034 -49.725072 90)
			(size 0.519938 1.4986)
			(layers "F.Cu" "F.Mask" "F.Paste")
			(net "GND")
		)
		(pad "18" smd rect
			(at -2.050034 -48.874934 90)
			(size 0.519938 1.4986)
			(layers "F.Cu" "F.Mask" "F.Paste")
			(net "M_J_CPU1_SA_DQ<8>")
		)
		(pad "19" smd rect
			(at -2.050034 -48.02505 90)
			(size 0.519938 1.4986)
			(layers "F.Cu" "F.Mask" "F.Paste")
			(net "GND")
		)
		(pad "20" smd rect
			(at -2.050034 -47.174912 90)
			(size 0.519938 1.4986)
			(layers "F.Cu" "F.Mask" "F.Paste")
			(net "M_J_CPU1_SA_DQ<9>")
		)
		(pad "21" smd rect
			(at -2.050034 -46.325028 90)
			(size 0.519938 1.4986)
			(layers "F.Cu" "F.Mask" "F.Paste")
			(net "GND")
		)
		(pad "22" smd rect
			(at -2.050034 -45.47489 90)
			(size 0.519938 1.4986)
			(layers "F.Cu" "F.Mask" "F.Paste")
			(net "M_J_CPU1_SA_DQS_DP<1>")
		)
		(pad "23" smd rect
			(at -2.050034 -44.625006 90)
			(size 0.519938 1.4986)
			(layers "F.Cu" "F.Mask" "F.Paste")
			(net "M_J_CPU1_SA_DQS_DN<1>")
		)
		(pad "24" smd rect
			(at -2.050034 -43.775122 90)
			(size 0.519938 1.4986)
			(layers "F.Cu" "F.Mask" "F.Paste")
			(net "GND")
		)
		(pad "25" smd rect
			(at -2.050034 -42.924984 90)
			(size 0.519938 1.4986)
			(layers "F.Cu" "F.Mask" "F.Paste")
			(net "M_J_CPU1_SA_DQ<12>")
		)
		(pad "26" smd rect
			(at -2.050034 -42.0751 90)
			(size 0.519938 1.4986)
			(layers "F.Cu" "F.Mask" "F.Paste")
			(net "GND")
		)
		(pad "27" smd rect
			(at -2.050034 -41.224962 90)
			(size 0.519938 1.4986)
			(layers "F.Cu" "F.Mask" "F.Paste")
			(net "M_J_CPU1_SA_DQ<13>")
		)
		(pad "28" smd rect
			(at -2.050034 -40.375078 90)
			(size 0.519938 1.4986)
			(layers "F.Cu" "F.Mask" "F.Paste")
			(net "GND")
		)
		(pad "29" smd rect
			(at -2.050034 -39.52494 90)
			(size 0.519938 1.4986)
			(layers "F.Cu" "F.Mask" "F.Paste")
			(net "M_J_CPU1_SA_DQ<16>")
		)
		(pad "30" smd rect
			(at -2.050034 -38.675056 90)
			(size 0.519938 1.4986)
			(layers "F.Cu" "F.Mask" "F.Paste")
			(net "GND")
		)
		(pad "31" smd rect
			(at -2.050034 -37.824918 90)
			(size 0.519938 1.4986)
			(layers "F.Cu" "F.Mask" "F.Paste")
			(net "M_J_CPU1_SA_DQ<17>")
		)
		(pad "32" smd rect
			(at -2.050034 -36.975034 90)
			(size 0.519938 1.4986)
			(layers "F.Cu" "F.Mask" "F.Paste")
			(net "GND")
		)
		(pad "33" smd rect
			(at -2.050034 -36.124896 90)
			(size 0.519938 1.4986)
			(layers "F.Cu" "F.Mask" "F.Paste")
			(net "M_J_CPU1_SA_DQS_DP<2>")
		)
		(pad "34" smd rect
			(at -2.050034 -35.275012 90)
			(size 0.519938 1.4986)
			(layers "F.Cu" "F.Mask" "F.Paste")
			(net "M_J_CPU1_SA_DQS_DN<2>")
		)
		(pad "35" smd rect
			(at -2.050034 -34.425128 90)
			(size 0.519938 1.4986)
			(layers "F.Cu" "F.Mask" "F.Paste")
			(net "GND")
		)
		(pad "36" smd rect
			(at -2.050034 -33.57499 90)
			(size 0.519938 1.4986)
			(layers "F.Cu" "F.Mask" "F.Paste")
			(net "M_J_CPU1_SA_DQ<20>")
		)
		(pad "37" smd rect
			(at -2.050034 -32.725106 90)
			(size 0.519938 1.4986)
			(layers "F.Cu" "F.Mask" "F.Paste")
			(net "GND")
		)
		(pad "38" smd rect
			(at -2.050034 -31.874968 90)
			(size 0.519938 1.4986)
			(layers "F.Cu" "F.Mask" "F.Paste")
			(net "M_J_CPU1_SA_DQ<21>")
		)
		(pad "39" smd rect
			(at -2.050034 -31.025084 90)
			(size 0.519938 1.4986)
			(layers "F.Cu" "F.Mask" "F.Paste")
			(net "GND")
		)
		(pad "40" smd rect
			(at -2.050034 -30.174946 90)
			(size 0.519938 1.4986)
			(layers "F.Cu" "F.Mask" "F.Paste")
			(net "M_J_CPU1_SA_DQ<24>")
		)
		(pad "41" smd rect
			(at -2.050034 -29.325062 90)
			(size 0.519938 1.4986)
			(layers "F.Cu" "F.Mask" "F.Paste")
			(net "GND")
		)
		(pad "42" smd rect
			(at -2.050034 -28.474924 90)
			(size 0.519938 1.4986)
			(layers "F.Cu" "F.Mask" "F.Paste")
			(net "M_J_CPU1_SA_DQ<25>")
		)
		(pad "43" smd rect
			(at -2.050034 -27.62504 90)
			(size 0.519938 1.4986)
			(layers "F.Cu" "F.Mask" "F.Paste")
			(net "GND")
		)
		(pad "44" smd rect
			(at -2.050034 -26.774902 90)
			(size 0.519938 1.4986)
			(layers "F.Cu" "F.Mask" "F.Paste")
			(net "M_J_CPU1_SA_DQS_DP<3>")
		)
		(pad "45" smd rect
			(at -2.050034 -25.925018 90)
			(size 0.519938 1.4986)
			(layers "F.Cu" "F.Mask" "F.Paste")
			(net "M_J_CPU1_SA_DQS_DN<3>")
		)
		(pad "46" smd rect
			(at -2.050034 -25.07488 90)
			(size 0.519938 1.4986)
			(layers "F.Cu" "F.Mask" "F.Paste")
			(net "GND")
		)
		(pad "47" smd rect
			(at -2.050034 -24.224996 90)
			(size 0.519938 1.4986)
			(layers "F.Cu" "F.Mask" "F.Paste")
			(net "M_J_CPU1_SA_DQ<28>")
		)
		(pad "48" smd rect
			(at -2.050034 -23.375112 90)
			(size 0.519938 1.4986)
			(layers "F.Cu" "F.Mask" "F.Paste")
			(net "GND")
		)
		(pad "49" smd rect
			(at -2.050034 -22.524974 90)
			(size 0.519938 1.4986)
			(layers "F.Cu" "F.Mask" "F.Paste")
			(net "M_J_CPU1_SA_DQ<29>")
		)
		(pad "50" smd rect
			(at -2.050034 -21.67509 90)
			(size 0.519938 1.4986)
			(layers "F.Cu" "F.Mask" "F.Paste")
			(net "GND")
		)
		(pad "51" smd rect
			(at -2.050034 -20.824952 90)
			(size 0.519938 1.4986)
			(layers "F.Cu" "F.Mask" "F.Paste")
			(net "M_J_CPU1_SA_CB<0>")
		)
		(pad "52" smd rect
			(at -2.050034 -19.975068 90)
			(size 0.519938 1.4986)
			(layers "F.Cu" "F.Mask" "F.Paste")
			(net "GND")
		)
		(pad "53" smd rect
			(at -2.050034 -19.12493 90)
			(size 0.519938 1.4986)
			(layers "F.Cu" "F.Mask" "F.Paste")
			(net "M_J_CPU1_SA_CB<1>")
		)
		(pad "54" smd rect
			(at -2.050034 -18.275046 90)
			(size 0.519938 1.4986)
			(layers "F.Cu" "F.Mask" "F.Paste")
			(net "GND")
		)
		(pad "55" smd rect
			(at -2.050034 -17.424908 90)
			(size 0.519938 1.4986)
			(layers "F.Cu" "F.Mask" "F.Paste")
			(net "M_J_CPU1_SA_DQS_DP<4>")
		)
		(pad "56" smd rect
			(at -2.050034 -16.575024 90)
			(size 0.519938 1.4986)
			(layers "F.Cu" "F.Mask" "F.Paste")
			(net "M_J_CPU1_SA_DQS_DN<4>")
		)
		(pad "57" smd rect
			(at -2.050034 -15.724886 90)
			(size 0.519938 1.4986)
			(layers "F.Cu" "F.Mask" "F.Paste")
			(net "GND")
		)
		(pad "58" smd rect
			(at -2.050034 -14.875002 90)
			(size 0.519938 1.4986)
			(layers "F.Cu" "F.Mask" "F.Paste")
			(net "M_J_CPU1_SA_CB<4>")
		)
		(pad "59" smd rect
			(at -2.050034 -14.025118 90)
			(size 0.519938 1.4986)
			(layers "F.Cu" "F.Mask" "F.Paste")
			(net "GND")
		)
		(pad "60" smd rect
			(at -2.050034 -13.17498 90)
			(size 0.519938 1.4986)
			(layers "F.Cu" "F.Mask" "F.Paste")
			(net "M_J_CPU1_SA_CB<5>")
		)
		(pad "61" smd rect
			(at -2.050034 -12.325096 90)
			(size 0.519938 1.4986)
			(layers "F.Cu" "F.Mask" "F.Paste")
			(net "GND")
		)
		(pad "62" smd rect
			(at -2.050034 -11.474958 90)
			(size 0.519938 1.4986)
			(layers "F.Cu" "F.Mask" "F.Paste")
			(net "M_J_CPU1_ALERT_N")
		)
		(pad "63" smd rect
			(at -2.050034 -10.625074 90)
			(size 0.519938 1.4986)
			(layers "F.Cu" "F.Mask" "F.Paste")
			(net "GND")
		)
		(pad "64" smd rect
			(at -2.050034 -9.774936 90)
			(size 0.519938 1.4986)
			(layers "F.Cu" "F.Mask" "F.Paste")
			(net "M_J_CPU1_SA_CS_N<0>")
		)
		(pad "65" smd rect
			(at -2.050034 -8.925052 90)
			(size 0.519938 1.4986)
			(layers "F.Cu" "F.Mask" "F.Paste")
			(net "GND")
		)
		(pad "66" smd rect
			(at -2.050034 -8.074914 90)
			(size 0.519938 1.4986)
			(layers "F.Cu" "F.Mask" "F.Paste")
			(net "M_J_CPU1_SA_CA<0>")
		)
		(pad "67" smd rect
			(at -2.050034 -7.22503 90)
			(size 0.519938 1.4986)
			(layers "F.Cu" "F.Mask" "F.Paste")
			(net "GND")
		)
		(pad "68" smd rect
			(at -2.050034 -6.374892 90)
			(size 0.519938 1.4986)
			(layers "F.Cu" "F.Mask" "F.Paste")
			(net "M_J_CPU1_SA_CA<2>")
		)
		(pad "69" smd rect
			(at -2.050034 -5.525008 90)
			(size 0.519938 1.4986)
			(layers "F.Cu" "F.Mask" "F.Paste")
			(net "GND")
		)
		(pad "70" smd rect
			(at -2.050034 -4.675124 90)
			(size 0.519938 1.4986)
			(layers "F.Cu" "F.Mask" "F.Paste")
			(net "M_J_CPU1_SA_CA<4>")
		)
		(pad "71" smd rect
			(at -2.050034 -3.824986 90)
			(size 0.519938 1.4986)
			(layers "F.Cu" "F.Mask" "F.Paste")
			(net "GND")
		)
		(pad "72" smd rect
			(at -2.050034 -2.975102 90)
			(size 0.519938 1.4986)
			(layers "F.Cu" "F.Mask" "F.Paste")
			(net "M_J_CPU1_SA_CA<6>")
		)
		(pad "73" smd rect
			(at -2.050034 -2.124964 90)
			(size 0.519938 1.4986)
			(layers "F.Cu" "F.Mask" "F.Paste")
			(net "GND")
		)
		(pad "74" smd rect
			(at -2.050034 -1.27508 90)
			(size 0.519938 1.4986)
			(layers "F.Cu" "F.Mask" "F.Paste")
			(net "M_J_CPU1_SA_PAR")
		)
		(pad "75" smd rect
			(at -2.050034 -0.424942 90)
			(size 0.519938 1.4986)
			(layers "F.Cu" "F.Mask" "F.Paste")
			(net "GND")
		)
		(pad "76" smd rect
			(at -2.050034 5.525008 90)
			(size 0.519938 1.4986)
			(layers "F.Cu" "F.Mask" "F.Paste")
			(net "M_J_CPU1_SB_CA<0>")
		)
		(pad "77" smd rect
			(at -2.050034 6.374892 90)
			(size 0.519938 1.4986)
			(layers "F.Cu" "F.Mask" "F.Paste")
			(net "GND")
		)
		(pad "78" smd rect
			(at -2.050034 7.22503 90)
			(size 0.519938 1.4986)
			(layers "F.Cu" "F.Mask" "F.Paste")
			(net "M_J_CPU1_SB_CA<2>")
		)
		(pad "79" smd rect
			(at -2.050034 8.074914 90)
			(size 0.519938 1.4986)
			(layers "F.Cu" "F.Mask" "F.Paste")
			(net "GND")
		)
		(pad "80" smd rect
			(at -2.050034 8.925052 90)
			(size 0.519938 1.4986)
			(layers "F.Cu" "F.Mask" "F.Paste")
			(net "M_J_CPU1_SB_CA<4>")
		)
		(pad "81" smd rect
			(at -2.050034 9.774936 90)
			(size 0.519938 1.4986)
			(layers "F.Cu" "F.Mask" "F.Paste")
			(net "GND")
		)
		(pad "82" smd rect
			(at -2.050034 10.625074 90)
			(size 0.519938 1.4986)
			(layers "F.Cu" "F.Mask" "F.Paste")
			(net "M_J_CPU1_SB_CA<6>")
		)
		(pad "83" smd rect
			(at -2.050034 11.474958 90)
			(size 0.519938 1.4986)
			(layers "F.Cu" "F.Mask" "F.Paste")
			(net "GND")
		)
		(pad "84" smd rect
			(at -2.050034 12.325096 90)
			(size 0.519938 1.4986)
			(layers "F.Cu" "F.Mask" "F.Paste")
			(net "M_J_CPU1_SB_CS_N<0>")
		)
		(pad "85" smd rect
			(at -2.050034 13.17498 90)
			(size 0.519938 1.4986)
			(layers "F.Cu" "F.Mask" "F.Paste")
			(net "GND")
		)
		(pad "86" smd rect
			(at -2.050034 14.025118 90)
			(size 0.519938 1.4986)
			(layers "F.Cu" "F.Mask" "F.Paste")
			(net "M_J_CPU1_SA_RSP<0>")
		)
		(pad "87" smd rect
			(at -2.050034 14.875002 90)
			(size 0.519938 1.4986)
			(layers "F.Cu" "F.Mask" "F.Paste")
			(net "M_J_CPU1_SB_RSP<0>")
		)
		(pad "88" smd rect
			(at -2.050034 15.724886 90)
			(size 0.519938 1.4986)
			(layers "F.Cu" "F.Mask" "F.Paste")
			(net "GND")
		)
		(pad "89" smd rect
			(at -2.050034 16.575024 90)
			(size 0.519938 1.4986)
			(layers "F.Cu" "F.Mask" "F.Paste")
			(net "M_J_CPU1_SB_CB<4>")
		)
		(pad "90" smd rect
			(at -2.050034 17.424908 90)
			(size 0.519938 1.4986)
			(layers "F.Cu" "F.Mask" "F.Paste")
			(net "GND")
		)
		(pad "91" smd rect
			(at -2.050034 18.275046 90)
			(size 0.519938 1.4986)
			(layers "F.Cu" "F.Mask" "F.Paste")
			(net "M_J_CPU1_SB_CB<5>")
		)
		(pad "92" smd rect
			(at -2.050034 19.12493 90)
			(size 0.519938 1.4986)
			(layers "F.Cu" "F.Mask" "F.Paste")
			(net "GND")
		)
		(pad "93" smd rect
			(at -2.050034 19.975068 90)
			(size 0.519938 1.4986)
			(layers "F.Cu" "F.Mask" "F.Paste")
			(net "M_J_CPU1_SB_DQS_DP<9>")
		)
		(pad "94" smd rect
			(at -2.050034 20.824952 90)
			(size 0.519938 1.4986)
			(layers "F.Cu" "F.Mask" "F.Paste")
			(net "M_J_CPU1_SB_DQS_DN<9>")
		)
		(pad "95" smd rect
			(at -2.050034 21.67509 90)
			(size 0.519938 1.4986)
			(layers "F.Cu" "F.Mask" "F.Paste")
			(net "GND")
		)
		(pad "96" smd rect
			(at -2.050034 22.524974 90)
			(size 0.519938 1.4986)
			(layers "F.Cu" "F.Mask" "F.Paste")
			(net "M_J_CPU1_SB_CB<0>")
		)
		(pad "97" smd rect
			(at -2.050034 23.375112 90)
			(size 0.519938 1.4986)
			(layers "F.Cu" "F.Mask" "F.Paste")
			(net "GND")
		)
		(pad "98" smd rect
			(at -2.050034 24.224996 90)
			(size 0.519938 1.4986)
			(layers "F.Cu" "F.Mask" "F.Paste")
			(net "M_J_CPU1_SB_CB<1>")
		)
		(pad "99" smd rect
			(at -2.050034 25.07488 90)
			(size 0.519938 1.4986)
			(layers "F.Cu" "F.Mask" "F.Paste")
			(net "GND")
		)
		(pad "100" smd rect
			(at -2.050034 25.925018 90)
			(size 0.519938 1.4986)
			(layers "F.Cu" "F.Mask" "F.Paste")
			(net "M_J_CPU1_SB_DQ<0>")
		)
		(pad "101" smd rect
			(at -2.050034 26.774902 90)
			(size 0.519938 1.4986)
			(layers "F.Cu" "F.Mask" "F.Paste")
			(net "GND")
		)
		(pad "102" smd rect
			(at -2.050034 27.62504 90)
			(size 0.519938 1.4986)
			(layers "F.Cu" "F.Mask" "F.Paste")
			(net "M_J_CPU1_SB_DQ<1>")
		)
		(pad "103" smd rect
			(at -2.050034 28.474924 90)
			(size 0.519938 1.4986)
			(layers "F.Cu" "F.Mask" "F.Paste")
			(net "GND")
		)
		(pad "104" smd rect
			(at -2.050034 29.325062 90)
			(size 0.519938 1.4986)
			(layers "F.Cu" "F.Mask" "F.Paste")
			(net "M_J_CPU1_SB_DQS_DP<0>")
		)
		(pad "105" smd rect
			(at -2.050034 30.174946 90)
			(size 0.519938 1.4986)
			(layers "F.Cu" "F.Mask" "F.Paste")
			(net "M_J_CPU1_SB_DQS_DN<0>")
		)
		(pad "106" smd rect
			(at -2.050034 31.025084 90)
			(size 0.519938 1.4986)
			(layers "F.Cu" "F.Mask" "F.Paste")
			(net "GND")
		)
		(pad "107" smd rect
			(at -2.050034 31.874968 90)
			(size 0.519938 1.4986)
			(layers "F.Cu" "F.Mask" "F.Paste")
			(net "M_J_CPU1_SB_DQ<4>")
		)
		(pad "108" smd rect
			(at -2.050034 32.725106 90)
			(size 0.519938 1.4986)
			(layers "F.Cu" "F.Mask" "F.Paste")
			(net "GND")
		)
		(pad "109" smd rect
			(at -2.050034 33.57499 90)
			(size 0.519938 1.4986)
			(layers "F.Cu" "F.Mask" "F.Paste")
			(net "M_J_CPU1_SB_DQ<5>")
		)
		(pad "110" smd rect
			(at -2.050034 34.425128 90)
			(size 0.519938 1.4986)
			(layers "F.Cu" "F.Mask" "F.Paste")
			(net "GND")
		)
		(pad "111" smd rect
			(at -2.050034 35.275012 90)
			(size 0.519938 1.4986)
			(layers "F.Cu" "F.Mask" "F.Paste")
			(net "M_J_CPU1_SB_DQ<8>")
		)
		(pad "112" smd rect
			(at -2.050034 36.124896 90)
			(size 0.519938 1.4986)
			(layers "F.Cu" "F.Mask" "F.Paste")
			(net "GND")
		)
		(pad "113" smd rect
			(at -2.050034 36.975034 90)
			(size 0.519938 1.4986)
			(layers "F.Cu" "F.Mask" "F.Paste")
			(net "M_J_CPU1_SB_DQ<9>")
		)
	)
)
